# S9S_MB_2U (Grand Teton) — schematic netlist excerpt (pin names and nets, part order shuffled) for the footprints in the layout excerpt that follows; sources: Cadence DE-HDL packaged netlist, KiCad conversion of 03242023_DA0F0TMBIJ0_F0T_Motherboard_J_brd_V01_OCP.brd

J80  PICOPROBE_BXA  DELTA-L 4.0 EMPTY  pkg TRIANG_LAUNCH_3PXB  page 308
  \1_p\  = DELTA_L_85_10INCH_IN4_DP
  \2_n\  = DELTA_L_85_10INCH_IN4_DN
  \3_g\  = DELTA_L_GND_1

(kicad_pcb
	(version 20260206)
	(generator "pcbnew")
	(generator_version "10.0")
	(general
		(thickness 1.6)
		(legacy_teardrops no)
	)
	(paper "A4")
	(title_block
		(title "03242023_DA0F0TMBIJ0_F0T_Motherboard_J_brd_V01_OCP.brd")
		(comment 1 "Grand Teton / footprints 4537-4537 of 6105")
	)
	(layers
		(0 "F.Cu" signal "TOP")
		(4 "In1.Cu" signal "GND")
		(6 "In2.Cu" signal "IN1")
		(8 "In3.Cu" signal "GND1")
		(10 "In4.Cu" signal "IN2")
		(12 "In5.Cu" signal "GND2")
		(14 "In6.Cu" signal "IN3")
		(16 "In7.Cu" signal "GND3")
		(18 "In8.Cu" signal "VCC")
		(20 "In9.Cu" signal "VCC1")
		(22 "In10.Cu" signal "GND4")
		(24 "In11.Cu" signal "IN4")
		(26 "In12.Cu" signal "GND5")
		(28 "In13.Cu" signal "IN5")
		(30 "In14.Cu" signal "GND6")
		(32 "In15.Cu" signal "IN6")
		(34 "In16.Cu" signal "GND7")
		(2 "B.Cu" signal "BOTTOM")
		(9 "F.Adhes" user "F.Adhesive")
		(11 "B.Adhes" user "B.Adhesive")
		(13 "F.Paste" user "Package Geometry/Pastemask Top")
		(15 "B.Paste" user "Package Geometry/Pastemask Bottom")
		(5 "F.SilkS" user "Ref Des/Silkscreen Top")
		(7 "B.SilkS" user "Ref Des/Silkscreen Bottom")
		(1 "F.Mask" user "Board Geometry/Soldermask Top")
		(3 "B.Mask" user "Board Geometry/Soldermask Bottom")
		(17 "Dwgs.User" user "User.Drawings")
		(19 "Cmts.User" user "User.Comments")
		(21 "Eco1.User" user "User.Eco1")
		(23 "Eco2.User" user "User.Eco2")
		(25 "Edge.Cuts" user "Board Geometry/Outline")
		(27 "Margin" user)
		(31 "F.CrtYd" user "Package Geometry/Place Bound Top")
		(29 "B.CrtYd" user "Package Geometry/Place Bound Bottom")
		(35 "F.Fab" user "Ref Des/Assembly Top")
		(33 "B.Fab" user "Ref Des/Assembly Bottom")
	)
	(footprint ""
		(layer "B.Cu")
		(at 182.14594 5.461 180)
		(property "Reference" "J80"
			(at 4.24561 -1.143 270)
			(unlocked yes)
			(layer "B.SilkS")
			(effects
				(font
					(size 0.7874 0.5842)
					(thickness 0.1524)
				)
				(justify left mirror)
			)
		)
		(property "Value" ""
			(at 0 0 0)
			(layer "B.Fab")
			(effects
				(font
					(size 1.27 1.27)
				)
				(justify mirror)
			)
		)
		(duplicate_pad_numbers_are_jumpers no)
		(fp_line
			(start 1.2192 2.1082)
			(end 1.2192 -2.1082)
			(stroke
				(width 0.1524)
				(type default)
			)
			(layer "B.SilkS")
		)
		(fp_line
			(start 1.2192 -2.1082)
			(end -1.2192 -2.1082)
			(stroke
				(width 0.1524)
				(type default)
			)
			(layer "B.SilkS")
		)
		(fp_line
			(start -1.2192 2.1082)
			(end 1.2192 2.1082)
			(stroke
				(width 0.1524)
				(type default)
			)
			(layer "B.SilkS")
		)
		(fp_line
			(start -1.2192 -2.1082)
			(end -1.2192 2.1082)
			(stroke
				(width 0.1524)
				(type default)
			)
			(layer "B.SilkS")
		)
		(pad "" np_thru_hole circle
			(at -3.4671 -1.27 90)
			(size 1.0414 1.0414)
			(drill 1.0414)
			(layers "*.Cu" "*.Mask")
			(clearance 0.381)
			(thermal_gap 0.381)
		)
		(pad "" np_thru_hole circle
			(at -3.4671 1.27 90)
			(size 1.0414 1.0414)
			(drill 1.0414)
			(layers "*.Cu" "*.Mask")
			(clearance 0.381)
			(thermal_gap 0.381)
		)
		(pad "" np_thru_hole circle
			(at 2.8829 -1.27 90)
			(size 1.0414 1.0414)
			(drill 1.0414)
			(layers "*.Cu" "*.Mask")
			(clearance 0.381)
			(thermal_gap 0.381)
		)
		(pad "" np_thru_hole circle
			(at 2.8829 1.27 90)
			(size 1.0414 1.0414)
			(drill 1.0414)
			(layers "*.Cu" "*.Mask")
			(clearance 0.381)
			(thermal_gap 0.381)
		)
		(pad "1" smd rect
			(at -0.8255 -0.249936 90)
			(size 0.3048 0.508)
			(layers "B.Cu" "B.Mask" "B.Paste")
			(net "DELTA_L_85_10INCH_IN4_DP")
		)
		(pad "2" smd rect
			(at -0.8255 0.249936 90)
			(size 0.3048 0.508)
			(layers "B.Cu" "B.Mask" "B.Paste")
			(net "DELTA_L_85_10INCH_IN4_DN")
		)
		(pad "3" smd circle
			(at 0 0)
			(size 0 0)
			(layers "B.Cu" "B.Mask" "B.Paste")
			(net "DELTA_L_GND_1")
		)
		(zone
			(layers "F.Cu" "B.Cu" "In1.Cu" "In2.Cu" "In3.Cu" "In4.Cu" "In5.Cu" "In6.Cu"
				"In7.Cu" "In8.Cu" "In9.Cu" "In10.Cu" "In11.Cu" "In12.Cu" "In13.Cu" "In14.Cu"
				"In15.Cu" "In16.Cu"
			)
			(hatch none 0.5)
			(connect_pads
				(clearance 0)
			)
			(min_thickness 0.25)
			(keepout
				(tracks not_allowed)
				(vias allowed)
				(pads allowed)
				(copperpour not_allowed)
				(footprints allowed)
			)
			(placement
				(enabled no)
				(sheetname "")
			)
			(fill
				(thermal_gap 0.5)
				(thermal_bridge_width 0.5)
				(island_removal_mode 0)
			)
			(polygon
				(pts
					(arc
						(start 180.19014 4.191)
						(mid 178.33594 4.191)
						(end 180.19014 4.191)
					)
				)
			)
		)
		(zone
			(layers "F.Cu" "B.Cu" "In1.Cu" "In2.Cu" "In3.Cu" "In4.Cu" "In5.Cu" "In6.Cu"
				"In7.Cu" "In8.Cu" "In9.Cu" "In10.Cu" "In11.Cu" "In12.Cu" "In13.Cu" "In14.Cu"
				"In15.Cu" "In16.Cu"
			)
			(hatch none 0.5)
			(connect_pads
				(clearance 0)
			)
			(min_thickness 0.25)
			(keepout
				(tracks not_allowed)
				(vias allowed)
				(pads allowed)
				(copperpour not_allowed)
				(footprints allowed)
			)
			(placement
				(enabled no)
				(sheetname "")
			)
			(fill
				(thermal_gap 0.5)
				(thermal_bridge_width 0.5)
				(island_removal_mode 0)
			)
			(polygon
				(pts
					(arc
						(start 180.19014 6.731)
						(mid 178.33594 6.731)
						(end 180.19014 6.731)
					)
				)
			)
		)
		(zone
			(layers "F.Cu" "B.Cu" "In1.Cu" "In2.Cu" "In3.Cu" "In4.Cu" "In5.Cu" "In6.Cu"
				"In7.Cu" "In8.Cu" "In9.Cu" "In10.Cu" "In11.Cu" "In12.Cu" "In13.Cu" "In14.Cu"
				"In15.Cu" "In16.Cu"
			)
			(hatch none 0.5)
			(connect_pads
				(clearance 0)
			)
			(min_thickness 0.25)
			(keepout
				(tracks not_allowed)
				(vias allowed)
				(pads allowed)
				(copperpour not_allowed)
				(footprints allowed)
			)
			(placement
				(enabled no)
				(sheetname "")
			)
			(fill
				(thermal_gap 0.5)
				(thermal_bridge_width 0.5)
				(island_removal_mode 0)
			)
			(polygon
				(pts
					(arc
						(start 186.54014 4.191)
						(mid 184.68594 4.191)
						(end 186.54014 4.191)
					)
				)
			)
		)
		(zone
			(layers "F.Cu" "B.Cu" "In1.Cu" "In2.Cu" "In3.Cu" "In4.Cu" "In5.Cu" "In6.Cu"
				"In7.Cu" "In8.Cu" "In9.Cu" "In10.Cu" "In11.Cu" "In12.Cu" "In13.Cu" "In14.Cu"
				"In15.Cu" "In16.Cu"
			)
			(hatch none 0.5)
			(connect_pads
				(clearance 0)
			)
			(min_thickness 0.25)
			(keepout
				(tracks not_allowed)
				(vias allowed)
				(pads allowed)
				(copperpour not_allowed)
				(footprints allowed)
			)
			(placement
				(enabled no)
				(sheetname "")
			)
			(fill
				(thermal_gap 0.5)
				(thermal_bridge_width 0.5)
				(island_removal_mode 0)
			)
			(polygon
				(pts
					(arc
						(start 186.54014 6.731)
						(mid 184.68594 6.731)
						(end 186.54014 6.731)
					)
				)
			)
		)
		(zone
			(layer "B.Cu")
			(hatch none 0.5)
			(connect_pads
				(clearance 0)
			)
			(min_thickness 0.25)
			(keepout
				(tracks not_allowed)
				(vias allowed)
				(pads allowed)
				(copperpour not_allowed)
				(footprints allowed)
			)
			(placement
				(enabled no)
				(sheetname "")
			)
			(fill
				(thermal_gap 0.5)
				(thermal_bridge_width 0.5)
				(island_removal_mode 0)
			)
			(polygon
				(pts
					(xy 183.26354 6.00964) (xy 183.26354 5.914136) (xy 182.66664 5.914136) (xy 182.66664 5.507736)
					(xy 183.26354 5.507736) (xy 183.26354 5.414264) (xy 182.66664 5.414264) (xy 182.66664 5.007864)
					(xy 183.26354 5.007864) (xy 183.26354 4.91236) (xy 182.56504 4.91236) (xy 182.56504 6.00964)
				)
			)
		)
	)
)
